# T6G (Grand Teton) — schematic netlist excerpt (pin names and nets, part order shuffled) for the footprints in the layout excerpt that follows; sources: Cadence DE-HDL packaged netlist, KiCad conversion of 04192023_DAF0TMB3IC0_F0TG_MB_C_brd_V02_OCP.brd

C305  Q_CAP  10PF 50V 5% EMPTY  pkg 0402  page 200 : A = SVID_PVDDCR_CPU1_P0_SVC_R ; B = GND

(kicad_pcb
	(version 20260206)
	(generator "pcbnew")
	(generator_version "10.0")
	(general
		(thickness 1.6)
		(legacy_teardrops no)
	)
	(paper "A4")
	(title_block
		(title "04192023_DAF0TMB3IC0_F0TG_MB_C_brd_V02_OCP.brd")
		(comment 1 "Grand Teton / footprints 4404-4404 of 8354")
	)
	(layers
		(0 "F.Cu" signal "TOP")
		(4 "In1.Cu" signal "GND")
		(6 "In2.Cu" signal "IN1")
		(8 "In3.Cu" signal "GND1")
		(10 "In4.Cu" signal "IN2")
		(12 "In5.Cu" signal "GND2")
		(14 "In6.Cu" signal "IN3")
		(16 "In7.Cu" signal "GND3")
		(18 "In8.Cu" signal "VCC")
		(20 "In9.Cu" signal "VCC1")
		(22 "In10.Cu" signal "GND4")
		(24 "In11.Cu" signal "IN4")
		(26 "In12.Cu" signal "GND5")
		(28 "In13.Cu" signal "IN5")
		(30 "In14.Cu" signal "GND6")
		(32 "In15.Cu" signal "IN6")
		(34 "In16.Cu" signal "GND7")
		(2 "B.Cu" signal "BOTTOM")
		(9 "F.Adhes" user "F.Adhesive")
		(11 "B.Adhes" user "B.Adhesive")
		(13 "F.Paste" user "Package Geometry/Pastemask Top")
		(15 "B.Paste" user "Package Geometry/Pastemask Bottom")
		(5 "F.SilkS" user "Ref Des/Silkscreen Top")
		(7 "B.SilkS" user "Ref Des/Silkscreen Bottom")
		(1 "F.Mask" user "Board Geometry/Soldermask Top")
		(3 "B.Mask" user "Board Geometry/Soldermask Bottom")
		(17 "Dwgs.User" user "User.Drawings")
		(19 "Cmts.User" user "User.Comments")
		(21 "Eco1.User" user "User.Eco1")
		(23 "Eco2.User" user "User.Eco2")
		(25 "Edge.Cuts" user "Board Geometry/Outline")
		(27 "Margin" user)
		(31 "F.CrtYd" user "Package Geometry/Place Bound Top")
		(29 "B.CrtYd" user "Package Geometry/Place Bound Bottom")
		(35 "F.Fab" user "Ref Des/Assembly Top")
		(33 "B.Fab" user "Ref Des/Assembly Bottom")
	)
	(footprint ""
		(layer "F.Cu")
		(at 302.133 -356.997 180)
		(property "Reference" "C305"
			(at 0 0 180)
			(layer "F.SilkS")
			(hide yes)
			(effects
				(font
					(size 1.27 1.27)
				)
			)
		)
		(property "Value" ""
			(at 0 0 180)
			(layer "F.Fab")
			(effects
				(font
					(size 1.27 1.27)
				)
			)
		)
		(duplicate_pad_numbers_are_jumpers no)
		(fp_line
			(start 0.7874 0.4064)
			(end -0.7874 0.4064)
			(stroke
				(width 0.1524)
				(type default)
			)
			(layer "F.SilkS")
		)
		(fp_line
			(start 0.7874 -0.4064)
			(end 0.7874 0.4064)
			(stroke
				(width 0.1524)
				(type default)
			)
			(layer "F.SilkS")
		)
		(fp_line
			(start -0.7874 0.4064)
			(end -0.7874 -0.4064)
			(stroke
				(width 0.1524)
				(type default)
			)
			(layer "F.SilkS")
		)
		(fp_line
			(start -0.7874 -0.4064)
			(end 0.7874 -0.4064)
			(stroke
				(width 0.1524)
				(type default)
			)
			(layer "F.SilkS")
		)
		(fp_line
			(start 0.67945 0.3048)
			(end 0.120396 0.3048)
			(stroke
				(width 0.1)
				(type default)
			)
			(layer "F.Fab")
		)
		(fp_line
			(start 0.67945 -0.3048)
			(end 0.67945 0.3048)
			(stroke
				(width 0.1)
				(type default)
			)
			(layer "F.Fab")
		)
		(fp_line
			(start 0.12065 -0.2794)
			(end 0.12065 -0.3048)
			(stroke
				(width 0.1)
				(type default)
			)
			(layer "F.Fab")
		)
		(fp_line
			(start 0.12065 -0.3048)
			(end 0.67945 -0.3048)
			(stroke
				(width 0.1)
				(type default)
			)
			(layer "F.Fab")
		)
		(fp_line
			(start 0.120396 0.3048)
			(end 0.120396 0.2794)
			(stroke
				(width 0.1)
				(type default)
			)
			(layer "F.Fab")
		)
		(fp_line
			(start 0.120396 0.2794)
			(end -0.12065 0.2794)
			(stroke
				(width 0.1)
				(type default)
			)
			(layer "F.Fab")
		)
		(fp_line
			(start -0.12065 0.3048)
			(end -0.67945 0.3048)
			(stroke
				(width 0.1)
				(type default)
			)
			(layer "F.Fab")
		)
		(fp_line
			(start -0.12065 0.2794)
			(end -0.12065 0.3048)
			(stroke
				(width 0.1)
				(type default)
			)
			(layer "F.Fab")
		)
		(fp_line
			(start -0.12065 -0.2794)
			(end 0.12065 -0.2794)
			(stroke
				(width 0.1)
				(type default)
			)
			(layer "F.Fab")
		)
		(fp_line
			(start -0.12065 -0.305054)
			(end -0.12065 -0.2794)
			(stroke
				(width 0.1)
				(type default)
			)
			(layer "F.Fab")
		)
		(fp_line
			(start -0.67945 0.3048)
			(end -0.67945 -0.305054)
			(stroke
				(width 0.1)
				(type default)
			)
			(layer "F.Fab")
		)
		(fp_line
			(start -0.67945 -0.305054)
			(end -0.12065 -0.305054)
			(stroke
				(width 0.1)
				(type default)
			)
			(layer "F.Fab")
		)
		(pad "1" smd circle
			(at -0.40005 0 180)
			(size 0 0)
			(layers "F.Cu" "F.Mask" "F.Paste")
			(net "SVID_PVDDCR_CPU1_P0_SVC_R")
		)
		(pad "2" smd circle
			(at 0.40005 0 180)
			(size 0 0)
			(layers "F.Cu" "F.Mask" "F.Paste")
			(net "GND")
		)
	)
)
